<schema xmlns="http://www.cadence.com/spb/csschema"
	xmlns:xsi="http://www.w3.org/2001/XMLSchema-instance"
	xsi:schemaLocation="http://www.cadence.com/spb/csschema CSSchema002.xsd">
  <header>
    <schemaVersion>16.5</schemaVersion>
    <creatorTool>conceptHDL</creatorTool>
    <modifierTool>conceptHDL</modifierTool>
    <modificationTime>2011-10-25T14:30:27</modificationTime>
    <savedLibrary>mstr_symbols</savedLibrary>
  </header>
  <designs>
    <design schemaType="nameBased" name="p5v" view="sch_1">
      <lastids>
        <netid>4</netid>
      </lastids>
      <cells>
      </cells>
      <nets>
        <net>
          <id>N1</id>
          <name>g</name>
          <scope>interface</scope>
          <direction>inout</direction>
        </net>
        <net>
          <id>N2</id>
          <name>page1_g</name>
        </net>
        <net>
          <id>N4</id>
          <name>page1_p5v</name>
        </net>
        <net>
          <id>N3</id>
          <name>p5v</name>
          <scope>global</scope>
        </net>
      </nets>
      <aliases>
        <alias net1="N2" lsb1="-1" msb1="-1" net2="N1" lsb2="-1" msb2="-1" />
        <alias net1="N4" lsb1="-1" msb1="-1" net2="N2" lsb2="-1" msb2="-1" />
        <alias net1="N4" lsb1="-1" msb1="-1" net2="N3" lsb2="-1" msb2="-1" />
      </aliases>
      <differentialnets>
      </differentialnets>
      <differentialbusnets>
      </differentialbusnets>
      <netgroups>
      </netgroups>
      <netinterfaces>
      </netinterfaces>
      <instances>
      </instances>
      <templateresolutions>
      </templateresolutions>
      <templateinstances>
      </templateinstances>
      <extensions>
        <extension name="schematic_extension">
        <schematicExtension>
        <netScopes>
          <netScope ref="g">
            <pageScope number="1">
              <scope>interface</scope>
              <direction>unknown</direction>
            </pageScope>
          </netScope>
          <netScope ref="p5v">
            <pageScope number="1">
              <scope>global</scope>
            </pageScope>
          </netScope>
        </netScopes>
        <pages>
          <page number="1">
            <physicalPageNumber>1</physicalPageNumber>
            <errorStatus>false</errorStatus>
            <nets>
              <net ref="g"></net>
              <net ref="p5v"></net>
            </nets>
            <instances>
            </instances>
          </page>
        </pages>
      </schematicExtension>
        </extension>
      </extensions>
    </design>
  </designs>
</schema>
